FILE_TYPE = CONNECTIVITY;
{Allegro Design Entry HDL 16.6-p007 (v16-6-112F) 10/10/2012}
"PAGE_NUMBER" = 218;
0"NC";
1"P3V3_STBY\g";
2"GND\g";
3"GND\g";
4"GND\g";
5"GND\g";
6"P3V3_STBY\g";
7"GND\g";
8"GND\g";
9"GND\g";
10"GND\g";
11"GND\g";
12"GND\g";
13"PVCCIO_CPU0\g";
14"VR_FET_SW_P12V_STBY_PVDDQ_DEF\g";
15"GND\g";
16"GND\g";
17"PVCCIO_CPU0\g";
18"GND\g";
19"VR_PVDDQ_DEF_VINSEN";
20"PWRGD_PVDDQ_DEF";
21"IRQ_PVDDQ_DEF_VRHOT_LVT3_N";
22"SVID_ALERT1_CPU0_R_N";
23"PU_VR_PVDDQ_DEF_FAULT1";
24"PWRGD_PVDDQ_DEF_R";
25"IRQ_PVDDQ_DEF_VRHOT_LVT3_R_N";
26"SVID_DIO1_CPU0_R";
27"SMB_VR_STBY_LVC3_SCL";
28"VR_PVDDQ_DEF_VD12";
29"SMB_VR_STBY_LVC3_SDA";
30"TP_PVDDQ_DEF_MP1";
31"SVID_ALERT_PVDDQ_DEF";
32"NC_PVDDQ_DEF_DNC1";
33"NC_PVDDQ_DEF_DNC0";
34"SVID_VDIO_PVDDQ_DEF";
35"SMB_VR_SCL_VDDQ_DEF";
36"SMB_VR_SDA_VDDQ_DEF";
37"TP_PVDDQ_DEF_PWM3";
38"TP_PVDDQ_DEF_BPWM1";
39"TP_PVDDQ_DEF_MP2";
40"TP_PVDDQ_DEF_PINALRT_N";
41"VR_PVDDQ_DEF_VD12";
42"VR_PVDDQ_DEF_PWM1";
43"VR_PVDDQ_DEF_PWM2";
44"VR_PVDDQ_DEF_VDD";
45"SVID_CLK_PVDDQ_DEF";
46"TP_PVDDQ_DEF_PH3_IMON_REF";
47"VR_PVDDQ_DEF_VREN";
48"TP_PVDDQ_DEF_BVREF";
49"TP_PVDDQ_DEF_BVSEN";
50"TP_PVDDQ_DEF_BTSEN";
51"TP_PVDDQ_DEF_PH3_IMON";
52"TP_PVDDQ_DEF_RESET_N";
53"TP_PVDDQ_DEF_BREF1";
54"VR_PVDDQ_DEF_XADDR1";
55"VR_PVDDQ_DEF_XADDR2";
56"VR_PVDDQ_DEF_AVSP";
57"VSENSE_PVDDQ_DEF_N";
58"VR_PVDDQ_DEF_AIREF1";
59"VR_PVDDQ_DEF_AIREF2";
60"VR_PVDDQ_DEF_AIINSEN";
61"A_TSENSE_PVDDQ_DEF";
62"ISENSE_PVDDQ_DEF_PH1_IMON";
63"ISENSE_PVDDQ_DEF_PH2_IMON";
64"VR_PVDDQ_DEF_VINSEN";
65"SVID_CLK1_CPU0_R";
66"VR_PVDDQ_DEF_VD12";
67"VSENSE_PVDDQ_DEF_P";
68"FM_PVDDQ_DEF_EN";
%"RES"
"1","(3100,2350)","0","mstr_discrete","I11";
;
CDS_LIB"mstr_discrete"
CDS_SEC"1"
$SEC"1"
CDS_LOCATION"R3M3"
ROOM"VDDQ_DEF_PWR_VR"
TOLERANCE"1.0%"
PACK_TYPE"0402"
LOCATION"R3M3"
PART_NUMBER"G21796-250"
VALUE"22.1"
MATERIAL"CHIP"
WATTAGE"1/16W";
"B"
$PN"2"20;
"A"
$PN"1"24;
%"RES"
"1","(3075,2250)","0","mstr_discrete","I12";
;
CDS_LIB"mstr_discrete"
$SEC"1"
CDS_SEC"1"
CDS_LOCATION"R7B1"
PACK_TYPE"0402"
TOLERANCE"1%"
MATERIAL"CHIP"
LOCATION"R7B1"
PART_NUMBER"G21796-074"
WATTAGE"1/16W"
VALUE"33.2";
"B"
$PN"2"21;
"A"
$PN"1"25;
%"P3V3_STBY"
"1","(2550,3575)","0","mstr_symbols","I13";
;
SIZE"1B"
CDS_LIB"mstr_symbols"
VOLTAGE"3.3V"
BODY_TYPE"PLUMBING"
HDL_POWER"P3V3_STBY";
"G\NAC"1;
%"RES"
"2","(2650,2725)","0","mstr_discrete","I14";
;
CDS_SEC"1"
SEC_TYPE"0402"
SEC"1"
CDS_LOCATION"R7A9"
ROOM"VDDQ_DEF_PWR_VR"
CDS_LIB"mstr_discrete"
MATERIAL"EMPTY"
PART_NUMBER"G21796-311"
VALUE"2.26K"
WATTAGE"1/16W"
LOCATION"R7A9"
TOLERANCE"1.0%"
PACK_TYPE"0402";
"A"
$PN"1"1;
"B"
$PN"2"23;
%"RES"
"1","(2525,2200)","0","mstr_discrete","I15";
;
CDS_SEC"1"
SEC"1"
SEC_TYPE"0402"
ROOM"VDDQ_DEF_PWR_VR"
CDS_LOCATION"R7A11"
CDS_LIB"mstr_discrete"
MATERIAL"CHIP"
PACK_TYPE"0402"
LOCATION"R7A11"
PART_NUMBER"G21497-005"
TOLERANCE"5%"
VALUE"0.0"
WATTAGE"1/16W";
"B"
$PN"2"22;
"A"
$PN"1"31;
%"RES"
"2","(2350,2900)","0","mstr_discrete","I16";
;
CDS_SEC"1"
SEC_TYPE"0402"
SEC"1"
ROOM"VDDQ_DEF_PWR_VR"
CDS_LIB"mstr_discrete"
CDS_LOCATION"R7B5"
PART_NUMBER"G21796-026"
WATTAGE"1/16W"
MATERIAL"CHIP"
TOLERANCE"1%"
VALUE"1.00K"
LOCATION"R7B5"
PACK_TYPE"0402";
"A"
$PN"1"1;
"B"
$PN"2"24;
%"RES"
"2","(2150,2900)","0","mstr_discrete","I17";
;
CDS_SEC"1"
ROOM"VDDQ_DEF_PWR_VR"
SEC"1"
SEC_TYPE"0402"
CDS_LOCATION"R7B4"
CDS_LIB"mstr_discrete"
LOCATION"R7B4"
VALUE"1.00K"
PACK_TYPE"0402"
MATERIAL"CHIP"
WATTAGE"1/16W"
TOLERANCE"1%"
PART_NUMBER"G21796-026";
"A"
$PN"1"1;
"B"
$PN"2"25;
%"RES"
"1","(3000,1850)","0","mstr_discrete","I21";
;
CDS_SEC"1"
$SEC"1"
CDS_LOCATION"R7B3"
CDS_LIB"mstr_discrete"
ROOM"VDDQ_DEF_PWR_VR"
PART_NUMBER"G21796-173"
PACK_TYPE"0402"
MATERIAL"CHIP"
LOCATION"R7B3"
VALUE"20.0"
TOLERANCE"1%"
WATTAGE"1/16W";
"B"
$PN"2"27;
"A"
$PN"1"35;
%"CAP_A"
"1","(3525,0)","0","dev_discrete","I22";
;
ROOM"VDDQ_DEF_PWR_VR"
SEC"1"
SEC_TYPE"0402V"
CDS_SEC"1"
CDS_LOCATION"C7B1"
CDS_LIB"dev_discrete"
LOCATION"C7B1"
VALUE"1.0UF"
VOLTAGE"6.3V"
PART_NUMBER"D97712-004"
TOLERANCE"10%"
PACK_TYPE"0402V"
MATERIAL"X6S";
"B"
$PN"2"8;
"A"
$PN"1"28;
%"CAP_A"
"1","(3125,0)","0","dev_discrete","I23";
;
SEC_TYPE"0402V"
ROOM"VDDQ_DEF_PWR_VR"
CDS_LOCATION"C7B2"
CDS_SEC"1"
SEC"1"
CDS_LIB"dev_discrete"
VALUE"0.1UF"
LOCATION"C7B2"
VOLTAGE"16V"
PART_NUMBER"A36096-030"
TOLERANCE"10%"
PACK_TYPE"0402V"
MATERIAL"X7R";
"B"
$PN"2"9;
"A"
$PN"1"28;
%"RES"
"1","(2675,1800)","0","mstr_discrete","I24";
;
ROOM"VDDQ_DEF_PWR_VR"
CDS_LOCATION"R7B2"
$SEC"1"
CDS_SEC"1"
CDS_LIB"mstr_discrete"
PART_NUMBER"G21796-173"
MATERIAL"CHIP"
LOCATION"R7B2"
TOLERANCE"1%"
PACK_TYPE"0402"
VALUE"20.0"
WATTAGE"1/16W";
"B"
$PN"2"29;
"A"
$PN"1"36;
%"RES"
"1","(2675,1500)","0","mstr_discrete","I25";
;
CDS_SEC"1"
ROOM"VDDQ_DEF_PWR_VR"
CDS_LOCATION"R7A12"
SEC"1"
SEC_TYPE"0402"
CDS_LIB"mstr_discrete"
LOCATION"R7A12"
PACK_TYPE"0402"
MATERIAL"CHIP"
TOLERANCE"5%"
PART_NUMBER"G21497-005"
VALUE"0.0"
WATTAGE"1/16W";
"B"
$PN"2"26;
"A"
$PN"1"34;
%"CAP"
"1","(2800,1025)","0","mstr_discrete","I26";
;
CDS_SEC"1"
SEC_TYPE"0402LF"
SEC"1"
CDS_LOCATION"C7B3"
ROOM"VDDQ_DEF_PWR_VR"
CDS_LIB"mstr_discrete"
PART_NUMBER"A36096-046"
LOCATION"C7B3"
VALUE"1000PF"
VOLTAGE"50V"
TOLERANCE"10%"
PACK_TYPE"0402LF"
MATERIAL"X7R";
"A"
$PN"1"24;
"B"
$PN"2"2;
%"GND"
"1","(2800,800)","0","mstr_symbols","I27";
;
SIZE"1B"
BODY_TYPE"PLUMBING"
CDS_LIB"mstr_symbols"
VOLTAGE"0"
HDL_POWER"GND"
ROOM"VDDQ_DEF_PWR_VR";
"A\NAC"2;
%"GND"
"1","(1900,625)","0","mstr_symbols","I28";
;
HDL_POWER"GND"
BODY_TYPE"PLUMBING"
SIZE"1B"
CDS_LIB"mstr_symbols"
VOLTAGE"0"
ROOM"VDDQ_DEF_PWR_VR";
"A\NAC"3;
%"CAP_A"
"1","(1425,2900)","0","dev_discrete","I29";
;
SEC"1"
SEC_TYPE"0402V"
CDS_SEC"1"
ROOM"VDDQ_DEF_PWR_VR"
CDS_LOCATION"C7A37"
CDS_LIB"dev_discrete"
LOCATION"C7A37"
PART_NUMBER"D97712-004"
VALUE"1.0UF"
TOLERANCE"10%"
PACK_TYPE"0402V"
VOLTAGE"6.3V"
MATERIAL"X6S";
"B"
$PN"2"4;
"A"
$PN"1"44;
%"GND"
"1","(1425,2700)","0","mstr_symbols","I30";
;
HDL_POWER"GND"
SIZE"1B"
CDS_LIB"mstr_symbols"
VOLTAGE"0"
BODY_TYPE"PLUMBING"
ROOM"VDDQ_DEF_PWR_VR";
"A\NAC"4;
%"CAP_A"
"1","(1025,2900)","0","dev_discrete","I31";
;
SEC"1"
SEC_TYPE"0402V"
ROOM"VDDQ_DEF_PWR_VR"
CDS_SEC"1"
CDS_LIB"dev_discrete"
CDS_LOCATION"C7A38"
PART_NUMBER"A36096-030"
VOLTAGE"16V"
TOLERANCE"10%"
VALUE"0.1UF"
LOCATION"C7A38"
MATERIAL"X7R"
PACK_TYPE"0402V";
"B"
$PN"2"5;
"A"
$PN"1"44;
%"GND"
"1","(1025,2700)","0","mstr_symbols","I32";
;
HDL_POWER"GND"
CDS_LIB"mstr_symbols"
SIZE"1B"
VOLTAGE"0"
BODY_TYPE"PLUMBING"
ROOM"VDDQ_DEF_PWR_VR";
"A\NAC"5;
%"P3V3_STBY"
"1","(725,3750)","0","mstr_symbols","I33";
;
SIZE"1B"
CDS_LIB"mstr_symbols"
VOLTAGE"3.3V"
BODY_TYPE"PLUMBING"
HDL_POWER"P3V3_STBY";
"G\NAC"6;
%"RES"
"2","(725,3250)","0","mstr_discrete","I34";
;
CDS_SEC"1"
ROOM"VDDQ_DEF_PWR_VR"
CDS_LOCATION"R3M1"
SEC"1"
SEC_TYPE"0402"
CDS_LIB"mstr_discrete"
PART_NUMBER"G21497-005"
TOLERANCE"5%"
VALUE"0.0"
LOCATION"R3M1"
WATTAGE"1/16W"
PACK_TYPE"0402"
MATERIAL"CHIP";
"A"
$PN"1"6;
"B"
$PN"2"44;
%"RES"
"2","(25,3325)","0","mstr_discrete","I35";
;
BOM_COST"SM_CONTROLLER"
CDS_SEC"1"
$SEC"1"
ROOM"VDDQ_DEF_PWR_VR"
CDS_LOCATION"R3M5"
CDS_LIB"mstr_discrete"
PART_NUMBER"G21796-010"
LOCATION"R3M5"
VALUE"100.0K"
TOLERANCE"1%"
MATERIAL"EMPTY"
PACK_TYPE"0402"
WATTAGE"1/16W";
"A"
$PN"1"6;
"B"
$PN"2"47;
%"RES"
"2","(400,100)","0","mstr_discrete","I37";
;
CDS_SEC"1"
$SEC"1"
ROOM"VDDQ_DEF_PWR_VR"
CDS_LIB"mstr_discrete"
CDS_LOCATION"R7A8"
LOCATION"R7A8"
VALUE"8.06K"
MATERIAL"CHIP"
WATTAGE"1/16W"
TOLERANCE"1%"
PART_NUMBER"G21796-078"
PACK_TYPE"0402";
"A"
$PN"1"55;
"B"
$PN"2"12;
%"GND"
"1","(0,650)","0","mstr_symbols","I38";
;
SIZE"1B"
VOLTAGE"0"
CDS_LIB"mstr_symbols"
HDL_POWER"GND"
BODY_TYPE"PLUMBING"
ROOM"VDDQ_DEF_PWR_VR";
"A\NAC"7;
%"CAP"
"1","(-75,550)","2","mstr_discrete","I39";
;
CDS_SEC"1"
SEC"1"
CDS_LOCATION"C7A29"
ROOM"VDDQ_DEF_PWR_VR"
CDS_LIB"mstr_discrete"
SEC_TYPE"0402LF"
VOLTAGE"50V"
MATERIAL"X7R"
VALUE"220PF"
LOCATION"C7A29"
TOLERANCE"10%"
PART_NUMBER"A36096-050"
PACK_TYPE"0402LF";
"A"
$PN"1"61;
"B"
$PN"2"10;
%"RES"
"2","(100,100)","0","mstr_discrete","I40";
;
ROOM"VDDQ_DEF_PWR_VR"
CDS_SEC"1"
$SEC"1"
CDS_LOCATION"R7A10"
CDS_LIB"mstr_discrete"
LOCATION"R7A10"
VALUE"3.16K"
MATERIAL"CHIP"
WATTAGE"1/16W"
TOLERANCE"1%"
PART_NUMBER"G21796-043"
PACK_TYPE"0402";
"A"
$PN"1"54;
"B"
$PN"2"11;
%"GND"
"1","(3525,-275)","0","mstr_symbols","I41";
;
SIZE"1B"
HDL_POWER"GND"
CDS_LIB"mstr_symbols"
VOLTAGE"0"
BODY_TYPE"PLUMBING"
ROOM"VDDQ_DEF_PWR_VR";
"A\NAC"8;
%"GND"
"1","(3125,-200)","0","mstr_symbols","I42";
;
SIZE"1B"
HDL_POWER"GND"
BODY_TYPE"PLUMBING"
CDS_LIB"mstr_symbols"
VOLTAGE"0"
ROOM"VDDQ_DEF_PWR_VR";
"A\NAC"9;
%"GND"
"1","(-75,-150)","0","mstr_symbols","I43";
;
SIZE"1B"
HDL_POWER"GND"
VOLTAGE"0"
CDS_LIB"mstr_symbols"
BODY_TYPE"PLUMBING"
ROOM"VDDQ_DEF_PWR_VR";
"A\NAC"10;
%"GND"
"1","(100,-150)","0","mstr_symbols","I44";
;
HDL_POWER"GND"
VOLTAGE"0"
CDS_LIB"mstr_symbols"
SIZE"1B"
BODY_TYPE"PLUMBING"
ROOM"VDDQ_DEF_PWR_VR";
"A\NAC"11;
%"GND"
"1","(400,-150)","0","mstr_symbols","I45";
;
HDL_POWER"GND"
VOLTAGE"0"
BODY_TYPE"PLUMBING"
SIZE"1B"
CDS_LIB"mstr_symbols"
ROOM"VDDQ_DEF_PWR_VR";
"A\NAC"12;
%"PVCCIO_CPU0"
"1","(-725,3775)","0","mstr_symbols","I46";
;
VOLTAGE"1.1V"
CDS_LIB"mstr_symbols"
BODY_TYPE"PLUMBING"
HDL_POWER"PVCCIO_CPU0";
"G\NAC"13;
%"RES"
"2","(-725,3350)","0","mstr_discrete","I47";
;
CDS_SEC"1"
SEC_TYPE"0402"
SEC"1"
CDS_LIB"mstr_discrete"
CDS_LOCATION"R3L13"
ROOM"VDDQ_DEF_PWR_VR"
MATERIAL"CHIP"
PART_NUMBER"G21796-047"
LOCATION"R3L13"
VALUE"49.9"
TOLERANCE"1%"
WATTAGE"1/16W"
PACK_TYPE"0402";
"A"
$PN"1"13;
"B"
$PN"2"65;
%"RES"
"1","(-300,2825)","0","mstr_discrete","I48";
;
CDS_SEC"1"
SEC_TYPE"0402"
SEC"1"
ROOM"VDDQ_DEF_PWR_VR"
CDS_LOCATION"R7A17"
CDS_LIB"mstr_discrete"
TOLERANCE"1%"
PACK_TYPE"0402"
MATERIAL"CHIP"
WATTAGE"1/16W"
PART_NUMBER"G21796-009"
LOCATION"R7A17"
VALUE"150.0";
"B"
$PN"2"45;
"A"
$PN"1"65;
%"RES"
"1","(-825,2650)","0","mstr_discrete","I50";
;
CDS_SEC"1"
$SEC"1"
CDS_LIB"mstr_discrete"
CDS_LOCATION"R3L10"
ROOM"VDDQ_DEF_PWR_VR"
PART_NUMBER"G21497-005"
LOCATION"R3L10"
VALUE"0.0"
TOLERANCE"5%"
PACK_TYPE"0402"
WATTAGE"1/16W"
MATERIAL"CHIP";
"B"
$PN"2"59;
"A"
$PN"1"66;
%"VCC_CORE"
"1","(-1350,3775)","0","mstr_symbols","I52";
;
CDS_LIB"mstr_symbols"
HDL_POWER"VR_FET_SW_P12V_STBY_PVDDQ_DEF";
"A"14;
%"RES"
"2","(-1350,3550)","0","mstr_discrete","I53";
;
CDS_SEC"1"
SEC_TYPE"0402"
SEC"1"
ROOM"VDDQ_DEF_PWR_VR"
CDS_LOCATION"R3L12"
CDS_LIB"mstr_discrete"
PART_NUMBER"G21796-160"
VALUE"100.0K"
LOCATION"R3L12"
TOLERANCE"1%"
PACK_TYPE"0402"
MATERIAL"CHIP"
WATTAGE"1/16W";
"A"
$PN"1"14;
"B"
$PN"2"19;
%"RES"
"2","(-1350,3175)","0","mstr_discrete","I54";
;
CDS_SEC"1"
SEC_TYPE"0402"
SEC"1"
ROOM"VDDQ_DEF_PWR_VR"
CDS_LOCATION"R7A16"
CDS_LIB"mstr_discrete"
PART_NUMBER"G21796-003"
LOCATION"R7A16"
VALUE"1.5K"
TOLERANCE"1%"
MATERIAL"CHIP"
WATTAGE"1/16W"
PACK_TYPE"0402";
"A"
$PN"1"19;
"B"
$PN"2"15;
%"CAP"
"1","(-1575,3175)","2","mstr_discrete","I55";
;
CDS_SEC"1"
SEC_TYPE"0402LF"
SEC"1"
ROOM"VDDQ_DEF_PWR_VR"
CDS_LOCATION"C7A35"
CDS_LIB"mstr_discrete"
TOLERANCE"10%"
MATERIAL"X7R"
PART_NUMBER"A36096-046"
VOLTAGE"50V"
LOCATION"C7A35"
VALUE"1000PF"
PACK_TYPE"0402LF";
"A"
$PN"1"19;
"B"
$PN"2"16;
%"GND"
"1","(-1350,2925)","0","mstr_symbols","I56";
;
HDL_POWER"GND"
SIZE"1B"
CDS_LIB"mstr_symbols"
BODY_TYPE"PLUMBING"
VOLTAGE"0"
ROOM"VDDQ_DEF_PWR_VR";
"A\NAC"15;
%"RES"
"1","(-1400,2475)","0","mstr_discrete","I57";
;
CDS_SEC"1"
$SEC"1"
ROOM"VDDQ_DEF_PWR_VR"
CDS_LIB"mstr_discrete"
CDS_LOCATION"R3L9"
PACK_TYPE"0402"
MATERIAL"CHIP"
LOCATION"R3L9"
TOLERANCE"5%"
PART_NUMBER"G21497-005"
VALUE"0.0"
WATTAGE"1/16W";
"B"
$PN"2"58;
"A"
$PN"1"66;
%"GND"
"1","(-1575,2925)","0","mstr_symbols","I58";
;
HDL_POWER"GND"
SIZE"1B"
BODY_TYPE"PLUMBING"
CDS_LIB"mstr_symbols"
VOLTAGE"0"
ROOM"VDDQ_DEF_PWR_VR";
"A\NAC"16;
%"RES"
"1","(-1725,1300)","0","mstr_discrete","I59";
;
CDS_SEC"1"
$SEC"1"
CDS_LIB"mstr_discrete"
CDS_LOCATION"R3M6"
ROOM"VDDQ_DEF_PWR_VR"
PACK_TYPE"0402"
LOCATION"R3M6"
TOLERANCE"5%"
MATERIAL"CHIP"
PART_NUMBER"G21497-005"
WATTAGE"1/16W"
VALUE"0.0";
"B"
$PN"2"47;
"A"
$PN"1"68;
%"PVCCIO_CPU0"
"1","(3700,3450)","0","mstr_symbols","I6";
;
VOLTAGE"1.1V"
CDS_LIB"mstr_symbols"
BODY_TYPE"PLUMBING"
HDL_POWER"PVCCIO_CPU0";
"G\NAC"17;
%"RES"
"1","(-1750,975)","0","mstr_discrete","I60";
;
CDS_SEC"1"
ROOM"VDDQ_DEF_PWR_VR"
SEC"1"
SEC_TYPE"0402"
CDS_LOCATION"R7A7"
CDS_LIB"mstr_discrete"
LOCATION"R7A7"
PACK_TYPE"0402"
MATERIAL"CHIP"
PART_NUMBER"G21796-066"
TOLERANCE"1%"
WATTAGE"1/16W"
VALUE"10.0";
"B"
$PN"2"56;
"A"
$PN"1"67;
%"CAP"
"1","(-1475,825)","0","mstr_discrete","I61";
;
CDS_SEC"1"
SEC_TYPE"0402LF"
SEC"1"
ROOM"VDDQ_DEF_PWR_VR"
CDS_LOCATION"C7A28"
CDS_LIB"mstr_discrete"
TOLERANCE"10%"
LOCATION"C7A28"
PART_NUMBER"A36096-050"
VALUE"220PF"
PACK_TYPE"0402LF"
MATERIAL"X7R"
VOLTAGE"50V";
"A"
$PN"1"56;
"B"
$PN"2"57;
%"RES"
"2","(3700,2725)","0","mstr_discrete","I7";
;
CDS_SEC"1"
SEC_TYPE"0402"
SEC"1"
CDS_LOCATION"R3L11"
ROOM"VDDQ_DEF_PWR_VR"
CDS_LIB"mstr_discrete"
MATERIAL"EMPTY"
LOCATION"R3L11"
PART_NUMBER"G21796-017"
VALUE"100.0"
WATTAGE"1/16W"
TOLERANCE"1%"
PACK_TYPE"0402";
"A"
$PN"1"17;
"B"
$PN"2"26;
%"PXM1310B"
"2","(1325,1600)","0","mstr_controller","I75";
;
CDS_SEC"1"
SEC"1"
SEC_TYPE"QFN"
PACK_TYPE"QFN"
CDS_LOCATION"EU7A5"
CDS_LMAN_SYM_OUTLINE"-400,900,400,-900"
CDS_LIB"mstr_controller"
LOCATION"EU7A5"
MATERIAL"IC"
PART_NUMBER"H89186-001";
"MP2"
$PN"18"39;
"MP1"
$PN"14"30;
"MP0"
$PN"13"23;
"AVREN"
$PN"10"47;
"AVRRDY"
$PN"9"24;
"IINSEN"
$PN"38"60;
"GND"
$PN"27"3;
"VD12"
$PN"40"41;
"VINSEN"
$PN"37"64;
"BVREF"
$PN"30"48;
"BVSEN"
$PN"29"49;
"AVREF"
$PN"20"57;
"AVSEN"
$PN"19"56;
"VALRT_N \B"
$PN"17"31;
"PINALRT_N \B"
$PN"12"40;
"VRHOT_N \B"
$PN"11"25;
"DNC<1>"
$PN"28"32;
"DNC<0>"
$PN"2"33;
"BIREF1"
$PN"31"53;
"BISEN1"
$PN"32"7;
"BTSEN"
$PN"34"50;
"VDD"
$PN"39"44;
"AIREF1"
$PN"21"58;
"AISEN1"
$PN"22"62;
"ATSEN"
$PN"35"61;
"AIREF2"
$PN"23"59;
"AISEN2"
$PN"24"63;
"XADDR2"
$PN"33"55;
"AIREF3"
$PN"25"46;
"AISEN3"
$PN"26"51;
"XADDR1"
$PN"36"54;
"RESET_N \B"
$PN"8"52;
"VDIO"
$PN"16"34;
"VCLK"
$PN"15"45;
"SCL"
$PN"7"35;
"SDA"
$PN"6"36;
"APWM3"
$PN"3"37;
"APWM2"
$PN"4"43;
"APWM1"
$PN"5"42;
"BPWM1"
$PN"1"38;
"THPAD"
$PN"41"3;
%"GND"
"1","(-800,0)","0","mstr_symbols","I76";
;
HDL_POWER"GND"
CDS_LIB"mstr_symbols"
BODY_TYPE"PLUMBING"
SIZE"1B"
VOLTAGE"0.0V";
"A\NAC"18;
%"CAP_A"
"1","(-800,350)","2","dev_discrete","I77";
;
CDS_LOCATION"C3L31"
SEC"1"
SEC_TYPE"0402V"
CDS_SEC"1"
ROOM"VDDQ_DEF_PWR_VR"
CDS_LIB"dev_discrete"
LOCATION"C3L31"
VALUE"0.1UF"
TOLERANCE"10%"
VOLTAGE"16V"
MATERIAL"X7R"
PACK_TYPE"0402V"
PART_NUMBER"A36096-030";
"B"
$PN"2"18;
"A"
$PN"1"60;
END.
